FILE_TYPE = MULTI_PHYS_TABLE;
PART 'CONN76_H22707001'
{===================================================================================================================================================================================================}
:PACK_TYPE | MATERIAL | PART_NUMBER     = EnvComp                  | PART_NUMBER  | JEDEC_TYPE          | DESCRIPTION                               | CLASS | COMPONENT_TYPE | HEIGHT     | LEAD_LENGTH   | SPEED_URL  | Status |RPL| AML | Bus_Unit | Days ;
{===================================================================================================================================================================================================}
'THMT'     | 'CONN'   | 'H22707-001'(!) = 'YES;YES;YES;UNK;ok;VLD' | 'H22707-001' | 'CONN76_H22707001'  | 'CONN,MISC,76P,RA RECEPT,VS2SMALLPF'      | 'IO'  | 'PRESSFIT'     | '0.459 IN' | '0.063' | 'http://speed.intel.com:8081/speed/module/pdm/item/pdm_item_detail_direct.asp?item_cde=H22707-001&item_rev=01&url_param=unused' | 'Design' | 'NO' | '1' | 'SMO_BOARDS' | '???' 
'THMT'     | 'EMPTY'  | 'H22707-001'(!) = 'YES;YES;YES;UNK;ok;VLD' | 'H22707-001' | 'CONN76_H22707001'  | 'CONN,MISC,76P,RA RECEPT,VS2SMALLPF'      | 'IO'  | 'PRESSFIT'     | '0.459 IN' | '0.063' | 'http://speed.intel.com:8081/speed/module/pdm/item/pdm_item_detail_direct.asp?item_cde=H22707-001&item_rev=01&url_param=unused' | 'Design' | 'NO' | '1' | 'SMO_BOARDS' | '???' 
'THMT1'    | 'CONN'   | 'H22707-001'(!) = 'YES;YES;YES;UNK;ok;VLD' | 'H22707-001' | 'CONN76_H22707001A' | 'CONN,MISC,76P,RA RECEPT,VS2SMALLPF'      | 'IO'  | 'PRESSFIT'     | '0.459 IN' | '0.063' | 'http://speed.intel.com:8081/speed/module/pdm/item/pdm_item_detail_direct.asp?item_cde=H22707-001&item_rev=01&url_param=unused' | 'Design' | 'NO' | '1' | 'SMO_BOARDS' | '???' 
'THMT1'    | 'EMPTY'  | 'H22707-001'(!) = 'YES;YES;YES;UNK;ok;VLD' | 'H22707-001' | 'CONN76_H22707001A' | 'CONN,MISC,76P,RA RECEPT,VS2SMALLPF'      | 'IO'  | 'PRESSFIT'     | '0.459 IN' | '0.063' | 'http://speed.intel.com:8081/speed/module/pdm/item/pdm_item_detail_direct.asp?item_cde=H22707-001&item_rev=01&url_param=unused' | 'Design' | 'NO' | '1' | 'SMO_BOARDS' | '???' 
END_PART
END.
